# BASEBOARD_FAB2 (Tioga Pass) — schematic netlist excerpt (pin names and nets, part order shuffled) for the footprints in the layout excerpt that follows; sources: Cadence DE-HDL packaged netlist, KiCad conversion of Wiwynn_Tioga_Pass_MB.brd

R7D27  RES  0.0 5% CHIP  pkg 0402  page 92 : A = H_CPU0_MSMI_G_N ; B = H_CPU_MSMI_G_N
C5D24  CAP_A  22.0UF 4V 20% X6S  pkg 0603V  page 42 : A = PVCCIN_CPU0 ; B = GND
C9A1  CAP_A  0.1UF 16V 10% X7R  pkg 0402V  page 155 : A = P5V_STBY_DGB_FS ; B = GND

(kicad_pcb
	(version 20260206)
	(generator "pcbnew")
	(generator_version "10.0")
	(general
		(thickness 1.6)
		(legacy_teardrops no)
	)
	(paper "A4")
	(title_block
		(title "Wiwynn_Tioga_Pass_MB.brd")
		(comment 1 "Tioga Pass / footprints 340-342 of 4770")
	)
	(layers
		(0 "F.Cu" signal "TOP")
		(4 "In1.Cu" signal "L2GND")
		(6 "In2.Cu" signal "L3")
		(8 "In3.Cu" signal "L4GND")
		(10 "In4.Cu" signal "L5")
		(12 "In5.Cu" signal "L6GND")
		(14 "In6.Cu" signal "L7VCC")
		(16 "In7.Cu" signal "L8VCC")
		(18 "In8.Cu" signal "L9GND")
		(20 "In9.Cu" signal "L10")
		(22 "In10.Cu" signal "L11GND")
		(24 "In11.Cu" signal "L12")
		(26 "In12.Cu" signal "L13GND")
		(2 "B.Cu" signal "BOTTOM")
		(9 "F.Adhes" user "F.Adhesive")
		(11 "B.Adhes" user "B.Adhesive")
		(13 "F.Paste" user "Package Geometry/Pastemask Top")
		(15 "B.Paste" user "Package Geometry/Pastemask Bottom")
		(5 "F.SilkS" user "Ref Des/Silkscreen Top")
		(7 "B.SilkS" user "Ref Des/Silkscreen Bottom")
		(1 "F.Mask" user "Board Geometry/Soldermask Top")
		(3 "B.Mask" user "Board Geometry/Soldermask Bottom")
		(17 "Dwgs.User" user "User.Drawings")
		(19 "Cmts.User" user "User.Comments")
		(21 "Eco1.User" user "User.Eco1")
		(23 "Eco2.User" user "User.Eco2")
		(25 "Edge.Cuts" user "Board Geometry/Outline")
		(27 "Margin" user)
		(31 "F.CrtYd" user "Package Geometry/Place Bound Top")
		(29 "B.CrtYd" user "Package Geometry/Place Bound Bottom")
		(35 "F.Fab" user "Ref Des/Assembly Top")
		(33 "B.Fab" user "Ref Des/Assembly Bottom")
	)
	(footprint ""
		(layer "F.Cu")
		(at 383.14757 -78.140814 90)
		(property "Reference" "R7D27"
			(at 0 0 90)
			(layer "F.SilkS")
			(hide yes)
			(effects
				(font
					(size 1.27 1.27)
				)
			)
		)
		(property "Value" ""
			(at 0 0 90)
			(layer "F.Fab")
			(effects
				(font
					(size 1.27 1.27)
				)
			)
		)
		(duplicate_pad_numbers_are_jumpers no)
		(fp_poly
			(pts
				(xy -0.2794 -0.1016) (xy 0.2794 -0.1016) (xy 0.2794 0.9906) (xy -0.2794 0.9906)
			)
			(stroke
				(width 0)
				(type default)
			)
			(fill no)
			(layer "F.CrtYd")
		)
		(fp_line
			(start 0.2794 -0.1016)
			(end -0.2794 -0.1016)
			(stroke
				(width 0.1)
				(type default)
			)
			(layer "F.Fab")
		)
		(fp_line
			(start -0.2794 -0.1016)
			(end -0.2794 0.9906)
			(stroke
				(width 0.1)
				(type default)
			)
			(layer "F.Fab")
		)
		(fp_line
			(start 0.2794 0.9906)
			(end 0.2794 -0.1016)
			(stroke
				(width 0.1)
				(type default)
			)
			(layer "F.Fab")
		)
		(fp_line
			(start -0.2794 0.9906)
			(end 0.2794 0.9906)
			(stroke
				(width 0.1)
				(type default)
			)
			(layer "F.Fab")
		)
		(pad "1" smd rect
			(at 0 0 90)
			(size 0.508 0.508)
			(layers "F.Cu" "F.Mask" "F.Paste")
			(net "H_CPU0_MSMI_G_N")
		)
		(pad "2" smd rect
			(at 0 0.889 90)
			(size 0.508 0.508)
			(layers "F.Cu" "F.Mask" "F.Paste")
			(net "H_CPU_MSMI_G_N")
		)
		(zone
			(layer "F.Cu")
			(hatch none 0.5)
			(connect_pads
				(clearance 0)
			)
			(min_thickness 0.25)
			(keepout
				(tracks allowed)
				(vias not_allowed)
				(pads allowed)
				(copperpour not_allowed)
				(footprints allowed)
			)
			(placement
				(enabled no)
				(sheetname "")
			)
			(fill
				(thermal_gap 0.5)
				(thermal_bridge_width 0.5)
				(island_removal_mode 0)
			)
			(polygon
				(pts
					(xy 383.40157 -77.886814) (xy 383.40157 -78.394814) (xy 383.78257 -78.394814) (xy 383.78257 -77.886814)
				)
			)
		)
		(zone
			(layer "F.Cu")
			(hatch none 0.5)
			(connect_pads
				(clearance 0)
			)
			(min_thickness 0.25)
			(keepout
				(tracks not_allowed)
				(vias allowed)
				(pads allowed)
				(copperpour not_allowed)
				(footprints allowed)
			)
			(placement
				(enabled no)
				(sheetname "")
			)
			(fill
				(thermal_gap 0.5)
				(thermal_bridge_width 0.5)
				(island_removal_mode 0)
			)
			(polygon
				(pts
					(xy 383.78257 -77.886814) (xy 383.78257 -78.394814) (xy 383.40157 -78.394814) (xy 383.40157 -77.886814)
				)
			)
		)
	)
	(footprint ""
		(layer "F.Cu")
		(at 490.35081 -155.293314 -90)
		(property "Reference" "C9A1"
			(at 0 0 270)
			(layer "F.SilkS")
			(hide yes)
			(effects
				(font
					(size 1.27 1.27)
				)
			)
		)
		(property "Value" ""
			(at 0 0 270)
			(layer "F.Fab")
			(effects
				(font
					(size 1.27 1.27)
				)
			)
		)
		(duplicate_pad_numbers_are_jumpers no)
		(fp_poly
			(pts
				(xy 0.3048 -0.1016) (xy 0.3048 0.9906) (xy -0.3048 0.9906) (xy -0.3048 -0.1016)
			)
			(stroke
				(width 0)
				(type default)
			)
			(fill no)
			(layer "F.CrtYd")
		)
		(fp_line
			(start -0.3048 0.9906)
			(end 0.3048 0.9906)
			(stroke
				(width 0.1)
				(type default)
			)
			(layer "F.Fab")
		)
		(fp_line
			(start 0.3048 0.9906)
			(end 0.3048 -0.1016)
			(stroke
				(width 0.1)
				(type default)
			)
			(layer "F.Fab")
		)
		(fp_line
			(start -0.3048 -0.1016)
			(end -0.3048 0.9906)
			(stroke
				(width 0.1)
				(type default)
			)
			(layer "F.Fab")
		)
		(fp_line
			(start 0.3048 -0.1016)
			(end -0.3048 -0.1016)
			(stroke
				(width 0.1)
				(type default)
			)
			(layer "F.Fab")
		)
		(pad "1" smd rect
			(at 0 0 270)
			(size 0.508 0.508)
			(layers "F.Cu" "F.Mask" "F.Paste")
			(net "P5V_STBY_DGB_FS")
		)
		(pad "2" smd rect
			(at 0 0.889 270)
			(size 0.508 0.508)
			(layers "F.Cu" "F.Mask" "F.Paste")
			(net "GND")
		)
		(zone
			(layer "F.Cu")
			(hatch none 0.5)
			(connect_pads
				(clearance 0)
			)
			(min_thickness 0.25)
			(keepout
				(tracks not_allowed)
				(vias allowed)
				(pads allowed)
				(copperpour not_allowed)
				(footprints allowed)
			)
			(placement
				(enabled no)
				(sheetname "")
			)
			(fill
				(thermal_gap 0.5)
				(thermal_bridge_width 0.5)
				(island_removal_mode 0)
			)
			(polygon
				(pts
					(xy 489.71581 -155.547314) (xy 489.71581 -155.039314) (xy 490.09681 -155.039314) (xy 490.09681 -155.547314)
				)
			)
		)
		(zone
			(layer "F.Cu")
			(hatch none 0.5)
			(connect_pads
				(clearance 0)
			)
			(min_thickness 0.25)
			(keepout
				(tracks allowed)
				(vias not_allowed)
				(pads allowed)
				(copperpour not_allowed)
				(footprints allowed)
			)
			(placement
				(enabled no)
				(sheetname "")
			)
			(fill
				(thermal_gap 0.5)
				(thermal_bridge_width 0.5)
				(island_removal_mode 0)
			)
			(polygon
				(pts
					(xy 490.09681 -155.547314) (xy 490.09681 -155.039314) (xy 489.71581 -155.039314) (xy 489.71581 -155.547314)
				)
			)
		)
	)
	(footprint ""
		(layer "F.Cu")
		(at 258.208272 -77.636116)
		(property "Reference" "C5D24"
			(at 0 0 0)
			(layer "F.SilkS")
			(hide yes)
			(effects
				(font
					(size 1.27 1.27)
				)
			)
		)
		(property "Value" ""
			(at 0 0 0)
			(layer "F.Fab")
			(effects
				(font
					(size 1.27 1.27)
				)
			)
		)
		(duplicate_pad_numbers_are_jumpers no)
		(fp_poly
			(pts
				(xy -0.4953 -0.2032) (xy 0.4953 -0.2032) (xy 0.4953 1.6002) (xy -0.4953 1.6002)
			)
			(stroke
				(width 0)
				(type default)
			)
			(fill no)
			(layer "F.CrtYd")
		)
		(fp_line
			(start -0.4953 -0.2032)
			(end 0.4953 -0.2032)
			(stroke
				(width 0.1)
				(type default)
			)
			(layer "F.Fab")
		)
		(fp_line
			(start -0.4953 1.6002)
			(end -0.4953 -0.2032)
			(stroke
				(width 0.1)
				(type default)
			)
			(layer "F.Fab")
		)
		(fp_line
			(start 0.4953 -0.2032)
			(end 0.4953 1.6002)
			(stroke
				(width 0.1)
				(type default)
			)
			(layer "F.Fab")
		)
		(fp_line
			(start 0.4953 1.6002)
			(end -0.4953 1.6002)
			(stroke
				(width 0.1)
				(type default)
			)
			(layer "F.Fab")
		)
		(pad "1" smd rect
			(at 0 0)
			(size 0.762 0.889)
			(layers "F.Cu" "F.Mask" "F.Paste")
			(net "PVCCIN_CPU0")
		)
		(pad "2" smd rect
			(at 0 1.397)
			(size 0.762 0.889)
			(layers "F.Cu" "F.Mask" "F.Paste")
			(net "GND")
		)
		(zone
			(layer "F.Cu")
			(hatch none 0.5)
			(connect_pads
				(clearance 0)
			)
			(min_thickness 0.25)
			(keepout
				(tracks not_allowed)
				(vias allowed)
				(pads allowed)
				(copperpour not_allowed)
				(footprints allowed)
			)
			(placement
				(enabled no)
				(sheetname "")
			)
			(fill
				(thermal_gap 0.5)
				(thermal_bridge_width 0.5)
				(island_removal_mode 0)
			)
			(polygon
				(pts
					(xy 257.827272 -77.191616) (xy 258.589272 -77.191616) (xy 258.589272 -76.683616) (xy 257.827272 -76.683616)
				)
			)
		)
	)
)
